# T6G (Grand Teton) — schematic netlist excerpt (pin names and nets, part order shuffled) for the footprints in the layout excerpt that follows; sources: Cadence DE-HDL packaged netlist, KiCad conversion of 04192023_DAF0TMB3IC0_F0TG_MB_C_brd_V02_OCP.brd

PC511_1  Q_CAP  1UF 25V 10% X6S  pkg C0402  page 225 : A = SW_P12V_AUX_PVDD11_S3_P1_FLT ; B = GND
PR4522  Q_RES  10M 1% CHIP  pkg 0402LF  page 140 : A = P12V_OCP_V3_2 ; B = P12V_OCP_GATE_2

(kicad_pcb
	(version 20260206)
	(generator "pcbnew")
	(generator_version "10.0")
	(general
		(thickness 1.6)
		(legacy_teardrops no)
	)
	(paper "A4")
	(title_block
		(title "04192023_DAF0TMB3IC0_F0TG_MB_C_brd_V02_OCP.brd")
		(comment 1 "Grand Teton / footprints 530-531 of 8354")
	)
	(layers
		(0 "F.Cu" signal "TOP")
		(4 "In1.Cu" signal "GND")
		(6 "In2.Cu" signal "IN1")
		(8 "In3.Cu" signal "GND1")
		(10 "In4.Cu" signal "IN2")
		(12 "In5.Cu" signal "GND2")
		(14 "In6.Cu" signal "IN3")
		(16 "In7.Cu" signal "GND3")
		(18 "In8.Cu" signal "VCC")
		(20 "In9.Cu" signal "VCC1")
		(22 "In10.Cu" signal "GND4")
		(24 "In11.Cu" signal "IN4")
		(26 "In12.Cu" signal "GND5")
		(28 "In13.Cu" signal "IN5")
		(30 "In14.Cu" signal "GND6")
		(32 "In15.Cu" signal "IN6")
		(34 "In16.Cu" signal "GND7")
		(2 "B.Cu" signal "BOTTOM")
		(9 "F.Adhes" user "F.Adhesive")
		(11 "B.Adhes" user "B.Adhesive")
		(13 "F.Paste" user "Package Geometry/Pastemask Top")
		(15 "B.Paste" user "Package Geometry/Pastemask Bottom")
		(5 "F.SilkS" user "Ref Des/Silkscreen Top")
		(7 "B.SilkS" user "Ref Des/Silkscreen Bottom")
		(1 "F.Mask" user "Board Geometry/Soldermask Top")
		(3 "B.Mask" user "Board Geometry/Soldermask Bottom")
		(17 "Dwgs.User" user "User.Drawings")
		(19 "Cmts.User" user "User.Comments")
		(21 "Eco1.User" user "User.Eco1")
		(23 "Eco2.User" user "User.Eco2")
		(25 "Edge.Cuts" user "Board Geometry/Outline")
		(27 "Margin" user)
		(31 "F.CrtYd" user "Package Geometry/Place Bound Top")
		(29 "B.CrtYd" user "Package Geometry/Place Bound Bottom")
		(35 "F.Fab" user "Ref Des/Assembly Top")
		(33 "B.Fab" user "Ref Des/Assembly Bottom")
	)
	(footprint ""
		(layer "F.Cu")
		(at 80.925162 -25.358598 180)
		(property "Reference" "PR4522"
			(at 0 0 180)
			(layer "F.SilkS")
			(hide yes)
			(effects
				(font
					(size 1.27 1.27)
				)
			)
		)
		(property "Value" ""
			(at 0 0 180)
			(layer "F.Fab")
			(effects
				(font
					(size 1.27 1.27)
				)
			)
		)
		(duplicate_pad_numbers_are_jumpers no)
		(fp_line
			(start 0.7874 0.4064)
			(end -0.7874 0.4064)
			(stroke
				(width 0.1524)
				(type default)
			)
			(layer "F.SilkS")
		)
		(fp_line
			(start 0.7874 -0.4064)
			(end 0.7874 0.4064)
			(stroke
				(width 0.1524)
				(type default)
			)
			(layer "F.SilkS")
		)
		(fp_line
			(start -0.7874 0.4064)
			(end -0.7874 -0.4064)
			(stroke
				(width 0.1524)
				(type default)
			)
			(layer "F.SilkS")
		)
		(fp_line
			(start -0.7874 -0.4064)
			(end 0.7874 -0.4064)
			(stroke
				(width 0.1524)
				(type default)
			)
			(layer "F.SilkS")
		)
		(fp_line
			(start 0.67945 0.3048)
			(end 0.120396 0.3048)
			(stroke
				(width 0.1)
				(type default)
			)
			(layer "F.Fab")
		)
		(fp_line
			(start 0.67945 -0.3048)
			(end 0.67945 0.3048)
			(stroke
				(width 0.1)
				(type default)
			)
			(layer "F.Fab")
		)
		(fp_line
			(start 0.12065 -0.2794)
			(end 0.12065 -0.3048)
			(stroke
				(width 0.1)
				(type default)
			)
			(layer "F.Fab")
		)
		(fp_line
			(start 0.12065 -0.3048)
			(end 0.67945 -0.3048)
			(stroke
				(width 0.1)
				(type default)
			)
			(layer "F.Fab")
		)
		(fp_line
			(start 0.120396 0.3048)
			(end 0.120396 0.2794)
			(stroke
				(width 0.1)
				(type default)
			)
			(layer "F.Fab")
		)
		(fp_line
			(start 0.120396 0.2794)
			(end -0.12065 0.2794)
			(stroke
				(width 0.1)
				(type default)
			)
			(layer "F.Fab")
		)
		(fp_line
			(start -0.12065 0.3048)
			(end -0.67945 0.3048)
			(stroke
				(width 0.1)
				(type default)
			)
			(layer "F.Fab")
		)
		(fp_line
			(start -0.12065 0.2794)
			(end -0.12065 0.3048)
			(stroke
				(width 0.1)
				(type default)
			)
			(layer "F.Fab")
		)
		(fp_line
			(start -0.12065 -0.2794)
			(end 0.12065 -0.2794)
			(stroke
				(width 0.1)
				(type default)
			)
			(layer "F.Fab")
		)
		(fp_line
			(start -0.12065 -0.305054)
			(end -0.12065 -0.2794)
			(stroke
				(width 0.1)
				(type default)
			)
			(layer "F.Fab")
		)
		(fp_line
			(start -0.67945 0.3048)
			(end -0.67945 -0.305054)
			(stroke
				(width 0.1)
				(type default)
			)
			(layer "F.Fab")
		)
		(fp_line
			(start -0.67945 -0.305054)
			(end -0.12065 -0.305054)
			(stroke
				(width 0.1)
				(type default)
			)
			(layer "F.Fab")
		)
		(pad "1" smd circle
			(at -0.40005 0 180)
			(size 0 0)
			(layers "F.Cu" "F.Mask" "F.Paste")
			(net "P12V_OCP_V3_2")
		)
		(pad "2" smd circle
			(at 0.40005 0 180)
			(size 0 0)
			(layers "F.Cu" "F.Mask" "F.Paste")
			(net "P12V_OCP_GATE_2")
		)
	)
	(footprint ""
		(layer "F.Cu")
		(at 186.577478 -351.383854 -90)
		(property "Reference" "PC511_1"
			(at 0 0 270)
			(layer "F.SilkS")
			(hide yes)
			(effects
				(font
					(size 1.27 1.27)
				)
			)
		)
		(property "Value" ""
			(at 0 0 270)
			(layer "F.Fab")
			(effects
				(font
					(size 1.27 1.27)
				)
			)
		)
		(duplicate_pad_numbers_are_jumpers no)
		(fp_line
			(start -0.7874 0.4064)
			(end -0.7874 -0.4064)
			(stroke
				(width 0.1524)
				(type default)
			)
			(layer "F.SilkS")
		)
		(fp_line
			(start 0.7874 0.4064)
			(end -0.7874 0.4064)
			(stroke
				(width 0.1524)
				(type default)
			)
			(layer "F.SilkS")
		)
		(fp_line
			(start -0.7874 -0.4064)
			(end 0.7874 -0.4064)
			(stroke
				(width 0.1524)
				(type default)
			)
			(layer "F.SilkS")
		)
		(fp_line
			(start 0.7874 -0.4064)
			(end 0.7874 0.4064)
			(stroke
				(width 0.1524)
				(type default)
			)
			(layer "F.SilkS")
		)
		(fp_line
			(start -0.67945 0.3048)
			(end -0.67945 -0.305054)
			(stroke
				(width 0.1)
				(type default)
			)
			(layer "F.Fab")
		)
		(fp_line
			(start -0.12065 0.3048)
			(end -0.67945 0.3048)
			(stroke
				(width 0.1)
				(type default)
			)
			(layer "F.Fab")
		)
		(fp_line
			(start 0.120396 0.3048)
			(end 0.120396 0.2794)
			(stroke
				(width 0.1)
				(type default)
			)
			(layer "F.Fab")
		)
		(fp_line
			(start 0.67945 0.3048)
			(end 0.120396 0.3048)
			(stroke
				(width 0.1)
				(type default)
			)
			(layer "F.Fab")
		)
		(fp_line
			(start -0.12065 0.2794)
			(end -0.12065 0.3048)
			(stroke
				(width 0.1)
				(type default)
			)
			(layer "F.Fab")
		)
		(fp_line
			(start 0.120396 0.2794)
			(end -0.12065 0.2794)
			(stroke
				(width 0.1)
				(type default)
			)
			(layer "F.Fab")
		)
		(fp_line
			(start -0.12065 -0.2794)
			(end 0.12065 -0.2794)
			(stroke
				(width 0.1)
				(type default)
			)
			(layer "F.Fab")
		)
		(fp_line
			(start 0.12065 -0.2794)
			(end 0.12065 -0.3048)
			(stroke
				(width 0.1)
				(type default)
			)
			(layer "F.Fab")
		)
		(fp_line
			(start 0.12065 -0.3048)
			(end 0.67945 -0.3048)
			(stroke
				(width 0.1)
				(type default)
			)
			(layer "F.Fab")
		)
		(fp_line
			(start 0.67945 -0.3048)
			(end 0.67945 0.3048)
			(stroke
				(width 0.1)
				(type default)
			)
			(layer "F.Fab")
		)
		(fp_line
			(start -0.67945 -0.305054)
			(end -0.12065 -0.305054)
			(stroke
				(width 0.1)
				(type default)
			)
			(layer "F.Fab")
		)
		(fp_line
			(start -0.12065 -0.305054)
			(end -0.12065 -0.2794)
			(stroke
				(width 0.1)
				(type default)
			)
			(layer "F.Fab")
		)
		(pad "1" smd circle
			(at -0.40005 0 270)
			(size 0 0)
			(layers "F.Cu" "F.Mask" "F.Paste")
			(net "SW_P12V_AUX_PVDD11_S3_P1_FLT")
		)
		(pad "2" smd circle
			(at 0.40005 0 270)
			(size 0 0)
			(layers "F.Cu" "F.Mask" "F.Paste")
			(net "GND")
		)
	)
)
